# S9S_MB_2U (Grand Teton) — schematic netlist excerpt (pin names and nets, part order shuffled) for the footprints in the layout excerpt that follows; sources: Cadence DE-HDL packaged netlist, KiCad conversion of 03242023_DA0F0TMBIJ0_F0T_Motherboard_J_brd_V01_OCP.brd

R2937  Q_RES  4.7K 5% CHIP  pkg 0402LF  page 151 : A = FM_GPU_PWR_EN_R ; B = GND
H18  HOLE  EMPTY  pkg TH  page 311 : \1\ = NC
R3301  Q_RES  33.2 1% CHIP  pkg 0402LF  page 190 : A = IRQ_LVC3_WAKE_N ; B = M2_0_PEWAKE_N

(kicad_pcb
	(version 20260206)
	(generator "pcbnew")
	(generator_version "10.0")
	(general
		(thickness 1.6)
		(legacy_teardrops no)
	)
	(paper "A4")
	(title_block
		(title "03242023_DA0F0TMBIJ0_F0T_Motherboard_J_brd_V01_OCP.brd")
		(comment 1 "Grand Teton / footprints 3669-3671 of 6105")
	)
	(layers
		(0 "F.Cu" signal "TOP")
		(4 "In1.Cu" signal "GND")
		(6 "In2.Cu" signal "IN1")
		(8 "In3.Cu" signal "GND1")
		(10 "In4.Cu" signal "IN2")
		(12 "In5.Cu" signal "GND2")
		(14 "In6.Cu" signal "IN3")
		(16 "In7.Cu" signal "GND3")
		(18 "In8.Cu" signal "VCC")
		(20 "In9.Cu" signal "VCC1")
		(22 "In10.Cu" signal "GND4")
		(24 "In11.Cu" signal "IN4")
		(26 "In12.Cu" signal "GND5")
		(28 "In13.Cu" signal "IN5")
		(30 "In14.Cu" signal "GND6")
		(32 "In15.Cu" signal "IN6")
		(34 "In16.Cu" signal "GND7")
		(2 "B.Cu" signal "BOTTOM")
		(9 "F.Adhes" user "F.Adhesive")
		(11 "B.Adhes" user "B.Adhesive")
		(13 "F.Paste" user "Package Geometry/Pastemask Top")
		(15 "B.Paste" user "Package Geometry/Pastemask Bottom")
		(5 "F.SilkS" user "Ref Des/Silkscreen Top")
		(7 "B.SilkS" user "Ref Des/Silkscreen Bottom")
		(1 "F.Mask" user "Board Geometry/Soldermask Top")
		(3 "B.Mask" user "Board Geometry/Soldermask Bottom")
		(17 "Dwgs.User" user "User.Drawings")
		(19 "Cmts.User" user "User.Comments")
		(21 "Eco1.User" user "User.Eco1")
		(23 "Eco2.User" user "User.Eco2")
		(25 "Edge.Cuts" user "Board Geometry/Outline")
		(27 "Margin" user)
		(31 "F.CrtYd" user "Package Geometry/Place Bound Top")
		(29 "B.CrtYd" user "Package Geometry/Place Bound Bottom")
		(35 "F.Fab" user "Ref Des/Assembly Top")
		(33 "B.Fab" user "Ref Des/Assembly Bottom")
	)
	(footprint ""
		(layer "F.Cu")
		(at 120.36044 -425.059348)
		(property "Reference" "R2937"
			(at 0 0 0)
			(layer "F.SilkS")
			(hide yes)
			(effects
				(font
					(size 1.27 1.27)
				)
			)
		)
		(property "Value" ""
			(at 0 0 0)
			(layer "F.Fab")
			(effects
				(font
					(size 1.27 1.27)
				)
			)
		)
		(duplicate_pad_numbers_are_jumpers no)
		(fp_line
			(start -0.7874 -0.4064)
			(end 0.7874 -0.4064)
			(stroke
				(width 0.1524)
				(type default)
			)
			(layer "F.SilkS")
		)
		(fp_line
			(start -0.7874 0.4064)
			(end -0.7874 -0.4064)
			(stroke
				(width 0.1524)
				(type default)
			)
			(layer "F.SilkS")
		)
		(fp_line
			(start 0.7874 -0.4064)
			(end 0.7874 0.4064)
			(stroke
				(width 0.1524)
				(type default)
			)
			(layer "F.SilkS")
		)
		(fp_line
			(start 0.7874 0.4064)
			(end -0.7874 0.4064)
			(stroke
				(width 0.1524)
				(type default)
			)
			(layer "F.SilkS")
		)
		(fp_line
			(start -0.67945 -0.305054)
			(end -0.12065 -0.305054)
			(stroke
				(width 0.1)
				(type default)
			)
			(layer "F.Fab")
		)
		(fp_line
			(start -0.67945 0.3048)
			(end -0.67945 -0.305054)
			(stroke
				(width 0.1)
				(type default)
			)
			(layer "F.Fab")
		)
		(fp_line
			(start -0.12065 -0.305054)
			(end -0.12065 -0.2794)
			(stroke
				(width 0.1)
				(type default)
			)
			(layer "F.Fab")
		)
		(fp_line
			(start -0.12065 -0.2794)
			(end 0.12065 -0.2794)
			(stroke
				(width 0.1)
				(type default)
			)
			(layer "F.Fab")
		)
		(fp_line
			(start -0.12065 0.2794)
			(end -0.12065 0.3048)
			(stroke
				(width 0.1)
				(type default)
			)
			(layer "F.Fab")
		)
		(fp_line
			(start -0.12065 0.3048)
			(end -0.67945 0.3048)
			(stroke
				(width 0.1)
				(type default)
			)
			(layer "F.Fab")
		)
		(fp_line
			(start 0.120396 0.2794)
			(end -0.12065 0.2794)
			(stroke
				(width 0.1)
				(type default)
			)
			(layer "F.Fab")
		)
		(fp_line
			(start 0.120396 0.3048)
			(end 0.120396 0.2794)
			(stroke
				(width 0.1)
				(type default)
			)
			(layer "F.Fab")
		)
		(fp_line
			(start 0.12065 -0.3048)
			(end 0.67945 -0.3048)
			(stroke
				(width 0.1)
				(type default)
			)
			(layer "F.Fab")
		)
		(fp_line
			(start 0.12065 -0.2794)
			(end 0.12065 -0.3048)
			(stroke
				(width 0.1)
				(type default)
			)
			(layer "F.Fab")
		)
		(fp_line
			(start 0.67945 -0.3048)
			(end 0.67945 0.3048)
			(stroke
				(width 0.1)
				(type default)
			)
			(layer "F.Fab")
		)
		(fp_line
			(start 0.67945 0.3048)
			(end 0.120396 0.3048)
			(stroke
				(width 0.1)
				(type default)
			)
			(layer "F.Fab")
		)
		(pad "1" smd circle
			(at -0.40005 0)
			(size 0 0)
			(layers "F.Cu" "F.Mask" "F.Paste")
			(net "FM_GPU_PWR_EN_R")
		)
		(pad "2" smd circle
			(at 0.40005 0)
			(size 0 0)
			(layers "F.Cu" "F.Mask" "F.Paste")
			(net "GND")
		)
	)
	(footprint ""
		(layer "F.Cu")
		(at 134.93496 -206.024734)
		(property "Reference" "H18"
			(at -1.17602 3.913632 0)
			(unlocked yes)
			(layer "F.SilkS")
			(effects
				(font
					(size 0.7874 0.5842)
					(thickness 0.1524)
				)
				(justify left)
			)
		)
		(property "Value" ""
			(at 0 0 0)
			(layer "F.Fab")
			(effects
				(font
					(size 1.27 1.27)
				)
			)
		)
		(duplicate_pad_numbers_are_jumpers no)
		(fp_circle
			(center 0 0)
			(end 2.5273 0)
			(stroke
				(width 0.1524)
				(type default)
			)
			(fill no)
			(layer "F.SilkS")
		)
		(fp_circle
			(center 0 0)
			(end 2.5273 0)
			(stroke
				(width 0.1524)
				(type default)
			)
			(fill no)
			(layer "B.SilkS")
		)
		(fp_circle
			(center 0 0)
			(end 2.5273 0)
			(stroke
				(width 0.1)
				(type default)
			)
			(fill no)
			(layer "B.Fab")
		)
		(fp_circle
			(center 0 0)
			(end 2.5273 0)
			(stroke
				(width 0.1)
				(type default)
			)
			(fill no)
			(layer "F.Fab")
		)
		(pad "" np_thru_hole circle
			(at 0 0)
			(size 3.429 3.429)
			(drill 3.429)
			(layers "*.Cu" "*.Mask")
			(clearance 0.381)
			(thermal_gap 0.381)
		)
	)
	(footprint ""
		(layer "F.Cu")
		(at 164.52088 -41.112948)
		(property "Reference" "R3301"
			(at 0 0 0)
			(layer "F.SilkS")
			(hide yes)
			(effects
				(font
					(size 1.27 1.27)
				)
			)
		)
		(property "Value" ""
			(at 0 0 0)
			(layer "F.Fab")
			(effects
				(font
					(size 1.27 1.27)
				)
			)
		)
		(duplicate_pad_numbers_are_jumpers no)
		(fp_line
			(start -0.7874 -0.4064)
			(end 0.7874 -0.4064)
			(stroke
				(width 0.1524)
				(type default)
			)
			(layer "F.SilkS")
		)
		(fp_line
			(start -0.7874 0.4064)
			(end -0.7874 -0.4064)
			(stroke
				(width 0.1524)
				(type default)
			)
			(layer "F.SilkS")
		)
		(fp_line
			(start 0.7874 -0.4064)
			(end 0.7874 0.4064)
			(stroke
				(width 0.1524)
				(type default)
			)
			(layer "F.SilkS")
		)
		(fp_line
			(start 0.7874 0.4064)
			(end -0.7874 0.4064)
			(stroke
				(width 0.1524)
				(type default)
			)
			(layer "F.SilkS")
		)
		(fp_line
			(start -0.67945 -0.305054)
			(end -0.12065 -0.305054)
			(stroke
				(width 0.1)
				(type default)
			)
			(layer "F.Fab")
		)
		(fp_line
			(start -0.67945 0.3048)
			(end -0.67945 -0.305054)
			(stroke
				(width 0.1)
				(type default)
			)
			(layer "F.Fab")
		)
		(fp_line
			(start -0.12065 -0.305054)
			(end -0.12065 -0.2794)
			(stroke
				(width 0.1)
				(type default)
			)
			(layer "F.Fab")
		)
		(fp_line
			(start -0.12065 -0.2794)
			(end 0.12065 -0.2794)
			(stroke
				(width 0.1)
				(type default)
			)
			(layer "F.Fab")
		)
		(fp_line
			(start -0.12065 0.2794)
			(end -0.12065 0.3048)
			(stroke
				(width 0.1)
				(type default)
			)
			(layer "F.Fab")
		)
		(fp_line
			(start -0.12065 0.3048)
			(end -0.67945 0.3048)
			(stroke
				(width 0.1)
				(type default)
			)
			(layer "F.Fab")
		)
		(fp_line
			(start 0.120396 0.2794)
			(end -0.12065 0.2794)
			(stroke
				(width 0.1)
				(type default)
			)
			(layer "F.Fab")
		)
		(fp_line
			(start 0.120396 0.3048)
			(end 0.120396 0.2794)
			(stroke
				(width 0.1)
				(type default)
			)
			(layer "F.Fab")
		)
		(fp_line
			(start 0.12065 -0.3048)
			(end 0.67945 -0.3048)
			(stroke
				(width 0.1)
				(type default)
			)
			(layer "F.Fab")
		)
		(fp_line
			(start 0.12065 -0.2794)
			(end 0.12065 -0.3048)
			(stroke
				(width 0.1)
				(type default)
			)
			(layer "F.Fab")
		)
		(fp_line
			(start 0.67945 -0.3048)
			(end 0.67945 0.3048)
			(stroke
				(width 0.1)
				(type default)
			)
			(layer "F.Fab")
		)
		(fp_line
			(start 0.67945 0.3048)
			(end 0.120396 0.3048)
			(stroke
				(width 0.1)
				(type default)
			)
			(layer "F.Fab")
		)
		(pad "1" smd circle
			(at -0.40005 0)
			(size 0 0)
			(layers "F.Cu" "F.Mask" "F.Paste")
			(net "IRQ_LVC3_WAKE_N")
		)
		(pad "2" smd circle
			(at 0.40005 0)
			(size 0 0)
			(layers "F.Cu" "F.Mask" "F.Paste")
			(net "M2_0_PEWAKE_N")
		)
	)
)
